(kicad_pcb
	(version 20260206)
	(generator "pcbnew")
	(generator_version "10.0")
	(general
		(thickness 1.6)
		(legacy_teardrops no)
	)
	(paper "A4")
	(title_block
		(title "Bryce Canyon_F.DPB_16315-1-OCP.brd")
		(comment 1 "Bryce Canyon / footprints 880-886 of 2223")
	)
	(layers
		(0 "F.Cu" signal "TOP")
		(4 "In1.Cu" signal "L2GND")
		(6 "In2.Cu" signal "L3")
		(8 "In3.Cu" signal "L4GND")
		(10 "In4.Cu" signal "L5")
		(12 "In5.Cu" signal "L6VCC")
		(14 "In6.Cu" signal "L7VCC")
		(16 "In7.Cu" signal "L8")
		(18 "In8.Cu" signal "L9GND")
		(20 "In9.Cu" signal "L10")
		(22 "In10.Cu" signal "L11GND")
		(2 "B.Cu" signal "BOTTOM")
		(9 "F.Adhes" user "F.Adhesive")
		(11 "B.Adhes" user "B.Adhesive")
		(13 "F.Paste" user "Package Geometry/Pastemask Top")
		(15 "B.Paste" user "Package Geometry/Pastemask Bottom")
		(5 "F.SilkS" user "Ref Des/Silkscreen Top")
		(7 "B.SilkS" user "Ref Des/Silkscreen Bottom")
		(1 "F.Mask" user "Board Geometry/Soldermask Top")
		(3 "B.Mask" user "Board Geometry/Soldermask Bottom")
		(17 "Dwgs.User" user "User.Drawings")
		(19 "Cmts.User" user "User.Comments")
		(21 "Eco1.User" user "User.Eco1")
		(23 "Eco2.User" user "User.Eco2")
		(25 "Edge.Cuts" user "Board Geometry/Outline")
		(27 "Margin" user)
		(31 "F.CrtYd" user "Package Geometry/Place Bound Top")
		(29 "B.CrtYd" user "Package Geometry/Place Bound Bottom")
		(35 "F.Fab" user "Ref Des/Assembly Top")
		(33 "B.Fab" user "Ref Des/Assembly Bottom")
	)
	(footprint ""
		(layer "F.Cu")
		(at 245.110254 -389.617204 -90)
		(property "Reference" "C585"
			(at 0 0 270)
			(layer "F.SilkS")
			(hide yes)
			(effects
				(font
					(size 1.27 1.27)
				)
			)
		)
		(property "Value" "SC1U25V3KX-GP"
			(at 0 -2.8194 270)
			(unlocked yes)
			(layer "F.Fab")
			(hide yes)
			(effects
				(font
					(size 1.016 1.016)
					(thickness 0.1524)
				)
			)
		)
		(property "Device Type" "C603H36"
			(at 0 -4.3434 270)
			(unlocked yes)
			(layer "F.Fab")
			(hide yes)
			(effects
				(font
					(size 1.016 1.016)
					(thickness 0.1524)
				)
			)
		)
		(duplicate_pad_numbers_are_jumpers no)
		(fp_line
			(start 0.508 0)
			(end -0.508 0)
			(stroke
				(width 0.2032)
				(type default)
			)
			(layer "F.SilkS")
		)
		(fp_rect
			(start -0.5842 1.3335)
			(end 0.5842 -1.3335)
			(stroke
				(width 0)
				(type default)
			)
			(fill no)
			(layer "F.CrtYd")
		)
		(fp_rect
			(start -0.5842 1.3335)
			(end 0.5842 -1.3335)
			(stroke
				(width 0)
				(type default)
			)
			(fill no)
			(layer "F.Fab")
		)
		(pad "1" smd custom
			(at 0 -0.762 270)
			(size 0.2159 0.2159)
			(layers "F.Cu" "F.Mask" "F.Paste")
			(net "AGND_CURRENT_DPB")
			(options
				(clearance outline)
				(anchor circle)
			)
			(primitives
				(gr_poly
					(pts
						(arc
							(start -0.3302 -0.4318)
							(mid -0.402042 -0.402042)
							(end -0.4318 -0.3302)
						)
						(arc
							(start -0.4318 0.3302)
							(mid -0.402042 0.402042)
							(end -0.3302 0.4318)
						)
						(arc
							(start 0.3302 0.4318)
							(mid 0.402042 0.402042)
							(end 0.4318 0.3302)
						)
						(arc
							(start 0.4318 -0.3302)
							(mid 0.402042 -0.402042)
							(end 0.3302 -0.4318)
						)
					)
					(width 0)
					(fill yes)
				)
			)
		)
		(pad "2" smd custom
			(at 0 0.762 270)
			(size 0.2159 0.2159)
			(layers "F.Cu" "F.Mask" "F.Paste")
			(net "MB3_P12V_HS")
			(options
				(clearance outline)
				(anchor circle)
			)
			(primitives
				(gr_poly
					(pts
						(arc
							(start -0.3302 -0.4318)
							(mid -0.402042 -0.402042)
							(end -0.4318 -0.3302)
						)
						(arc
							(start -0.4318 0.3302)
							(mid -0.402042 0.402042)
							(end -0.3302 0.4318)
						)
						(arc
							(start 0.3302 0.4318)
							(mid 0.402042 0.402042)
							(end 0.4318 0.3302)
						)
						(arc
							(start 0.4318 -0.3302)
							(mid 0.402042 -0.402042)
							(end 0.3302 -0.4318)
						)
					)
					(width 0)
					(fill yes)
				)
			)
		)
	)
	(footprint ""
		(layer "F.Cu")
		(at 450.9389 -277.750016 -90)
		(property "Reference" "VIA21"
			(at 0 0 270)
			(layer "F.SilkS")
			(hide yes)
			(effects
				(font
					(size 1.27 1.27)
				)
			)
		)
		(property "Value" "100OHM-8L-1D6MM-L18L16-GP"
			(at -3.7211 -4.5085 270)
			(unlocked yes)
			(layer "F.Fab")
			(hide yes)
			(effects
				(font
					(size 1.016 1.016)
					(thickness 0.1524)
				)
			)
		)
		(property "Device Type" "VIA-PCIE-4P-394076"
			(at -3.7211 -6.0325 270)
			(unlocked yes)
			(layer "F.Fab")
			(hide yes)
			(effects
				(font
					(size 1.016 1.016)
					(thickness 0.1524)
				)
			)
		)
		(duplicate_pad_numbers_are_jumpers no)
		(fp_rect
			(start -1.9685 0.381)
			(end 1.9685 -0.381)
			(stroke
				(width 0)
				(type default)
			)
			(fill no)
			(layer "F.CrtYd")
		)
		(fp_rect
			(start -1.9685 0.381)
			(end 1.9685 -0.381)
			(stroke
				(width 0)
				(type default)
			)
			(fill no)
			(layer "F.Fab")
		)
		(pad "1" thru_hole circle
			(at -1.5875 0 270)
			(size 0.508 0.508)
			(drill 0.254)
			(layers "*.Cu" "*.Mask")
			(remove_unused_layers no)
			(net "GND")
			(clearance 0.127)
			(thermal_gap 0.127)
		)
		(pad "2" thru_hole circle
			(at -0.5715 0 270)
			(size 0.508 0.508)
			(drill 0.254)
			(layers "*.Cu" "*.Mask")
			(remove_unused_layers no)
			(net "PHY_DRV_A_TO_SCC_A_10_DP")
			(clearance 0.127)
			(thermal_gap 0.127)
		)
		(pad "3" thru_hole circle
			(at 0.5715 0 270)
			(size 0.508 0.508)
			(drill 0.254)
			(layers "*.Cu" "*.Mask")
			(remove_unused_layers no)
			(net "PHY_DRV_A_TO_SCC_A_10_DN")
			(clearance 0.127)
			(thermal_gap 0.127)
		)
		(pad "4" thru_hole circle
			(at 1.5875 0 270)
			(size 0.508 0.508)
			(drill 0.254)
			(layers "*.Cu" "*.Mask")
			(remove_unused_layers no)
			(net "GND")
			(clearance 0.127)
			(thermal_gap 0.127)
		)
	)
	(footprint ""
		(layer "F.Cu")
		(at 141.042898 -284.523942 90)
		(property "Reference" "C101"
			(at 0 0 90)
			(layer "F.SilkS")
			(hide yes)
			(effects
				(font
					(size 1.27 1.27)
				)
			)
		)
		(property "Value" "SCD033U25V2KX-GP"
			(at 1.1811 -2.7051 90)
			(unlocked yes)
			(layer "F.Fab")
			(hide yes)
			(effects
				(font
					(size 1.016 1.016)
					(thickness 0.1524)
				)
			)
		)
		(property "Device Type" "C402H22"
			(at 1.1811 -4.2291 90)
			(unlocked yes)
			(layer "F.Fab")
			(hide yes)
			(effects
				(font
					(size 1.016 1.016)
					(thickness 0.1524)
				)
			)
		)
		(duplicate_pad_numbers_are_jumpers no)
		(fp_rect
			(start -0.4318 0.9525)
			(end 0.4318 -0.9525)
			(stroke
				(width 0)
				(type default)
			)
			(fill no)
			(layer "F.CrtYd")
		)
		(fp_rect
			(start -0.4318 0.9525)
			(end 0.4318 -0.9525)
			(stroke
				(width 0)
				(type default)
			)
			(fill no)
			(layer "F.Fab")
		)
		(pad "1" smd custom
			(at 0 -0.4445 90)
			(size 0.1524 0.1524)
			(layers "F.Cu" "F.Mask" "F.Paste")
			(net "P12V_A")
			(options
				(clearance outline)
				(anchor circle)
			)
			(primitives
				(gr_poly
					(pts
						(arc
							(start 0.3048 -0.2032)
							(mid 0.275042 -0.275042)
							(end 0.2032 -0.3048)
						)
						(arc
							(start -0.2032 -0.3048)
							(mid -0.275042 -0.275042)
							(end -0.3048 -0.2032)
						)
						(arc
							(start -0.3048 0.2032)
							(mid -0.275042 0.275042)
							(end -0.2032 0.3048)
						)
						(arc
							(start 0.2032 0.3048)
							(mid 0.275042 0.275042)
							(end 0.3048 0.2032)
						)
					)
					(width 0)
					(fill yes)
				)
			)
		)
		(pad "2" smd custom
			(at 0 0.4445 90)
			(size 0.1524 0.1524)
			(layers "F.Cu" "F.Mask" "F.Paste")
			(net "SW_HDD_N4")
			(options
				(clearance outline)
				(anchor circle)
			)
			(primitives
				(gr_poly
					(pts
						(arc
							(start 0.3048 -0.2032)
							(mid 0.275042 -0.275042)
							(end 0.2032 -0.3048)
						)
						(arc
							(start -0.2032 -0.3048)
							(mid -0.275042 -0.275042)
							(end -0.3048 -0.2032)
						)
						(arc
							(start -0.3048 0.2032)
							(mid -0.275042 0.275042)
							(end -0.2032 0.3048)
						)
						(arc
							(start 0.2032 0.3048)
							(mid 0.275042 0.275042)
							(end 0.3048 0.2032)
						)
					)
					(width 0)
					(fill yes)
				)
			)
		)
	)
	(footprint ""
		(layer "F.Cu")
		(at 441.349892 -94.400116)
		(property "Reference" "FLED23"
			(at 0 0 0)
			(layer "F.SilkS")
			(hide yes)
			(effects
				(font
					(size 1.27 1.27)
				)
			)
		)
		(property "Value" "LED-BY-19-GP"
			(at -2.132076 1.414018 0)
			(unlocked yes)
			(layer "F.Fab")
			(hide yes)
			(effects
				(font
					(size 1.016 1.016)
					(thickness 0.1524)
				)
			)
		)
		(property "Device Type" "LED-1615-4PH26"
			(at -2.132076 -0.109982 0)
			(unlocked yes)
			(layer "F.Fab")
			(hide yes)
			(effects
				(font
					(size 1.016 1.016)
					(thickness 0.1524)
				)
			)
		)
		(duplicate_pad_numbers_are_jumpers no)
		(fp_line
			(start -1.2954 0.254)
			(end -1.2954 1.6002)
			(stroke
				(width 0.508)
				(type default)
			)
			(layer "F.SilkS")
		)
		(fp_line
			(start -1.2954 1.6002)
			(end 1.2954 1.6002)
			(stroke
				(width 0.508)
				(type default)
			)
			(layer "F.SilkS")
		)
		(fp_line
			(start -1.1176 -1.4224)
			(end 1.1176 -1.4224)
			(stroke
				(width 0.1524)
				(type default)
			)
			(layer "F.SilkS")
		)
		(fp_line
			(start -1.1176 1.4224)
			(end -1.1176 -1.4224)
			(stroke
				(width 0.1524)
				(type default)
			)
			(layer "F.SilkS")
		)
		(fp_line
			(start 1.1176 -1.4224)
			(end 1.1176 1.4224)
			(stroke
				(width 0.1524)
				(type default)
			)
			(layer "F.SilkS")
		)
		(fp_line
			(start 1.1176 1.4224)
			(end -1.1176 1.4224)
			(stroke
				(width 0.1524)
				(type default)
			)
			(layer "F.SilkS")
		)
		(fp_line
			(start 1.2954 1.6002)
			(end 1.2954 0.254)
			(stroke
				(width 0.508)
				(type default)
			)
			(layer "F.SilkS")
		)
		(fp_rect
			(start -0.7493 0.8001)
			(end 0.7493 -0.8001)
			(stroke
				(width 0)
				(type default)
			)
			(fill no)
			(layer "F.CrtYd")
		)
		(fp_poly
			(pts
				(xy -1.3716 1.6764) (xy -1.3716 -1.6764) (xy 1.3716 -1.6764) (xy 1.3716 0.0635) (xy 0.7493 0.0635)
				(xy 0.7493 -0.8001) (xy -0.7493 -0.8001) (xy -0.7493 0.8001) (xy 0.7493 0.8001) (xy 0.7493 0.0762)
				(xy 1.3716 0.0762) (xy 1.3716 1.6764)
			)
			(stroke
				(width 0)
				(type default)
			)
			(fill no)
			(layer "F.CrtYd")
		)
		(fp_rect
			(start -1.3716 1.6764)
			(end 1.3716 -1.6764)
			(stroke
				(width 0)
				(type default)
			)
			(fill no)
			(layer "F.Fab")
		)
		(pad "1" smd rect
			(at 0.50038 -0.73025)
			(size 0.7112 0.8636)
			(layers "F.Cu" "F.Mask" "F.Paste")
			(net "DRV_ACT_22")
		)
		(pad "2" smd rect
			(at -0.50038 -0.73025)
			(size 0.7112 0.8636)
			(layers "F.Cu" "F.Mask" "F.Paste")
			(net "FLT_HDD22")
		)
		(pad "3" smd rect
			(at 0.50038 0.73025)
			(size 0.7112 0.8636)
			(layers "F.Cu" "F.Mask" "F.Paste")
			(net "DRV_ACT_22_N")
		)
		(pad "4" smd rect
			(at -0.50038 0.73025)
			(size 0.7112 0.8636)
			(layers "F.Cu" "F.Mask" "F.Paste")
			(net "FLT_HDD22_N")
		)
	)
	(footprint ""
		(layer "F.Cu")
		(at 341.965534 -294.424862 180)
		(property "Reference" "R287"
			(at 0 0 180)
			(layer "F.SilkS")
			(hide yes)
			(effects
				(font
					(size 1.27 1.27)
				)
			)
		)
		(property "Value" "91R3F-1-GP"
			(at -0.0254 -2.5146 180)
			(unlocked yes)
			(layer "F.Fab")
			(hide yes)
			(effects
				(font
					(size 1.016 1.016)
					(thickness 0.1524)
				)
			)
		)
		(property "Device Type" "R603H22"
			(at -0.0254 -4.0386 180)
			(unlocked yes)
			(layer "F.Fab")
			(hide yes)
			(effects
				(font
					(size 1.016 1.016)
					(thickness 0.1524)
				)
			)
		)
		(duplicate_pad_numbers_are_jumpers no)
		(fp_line
			(start 0.2032 0)
			(end 0.4826 0)
			(stroke
				(width 0.2032)
				(type default)
			)
			(layer "F.SilkS")
		)
		(fp_line
			(start -0.4826 0)
			(end -0.2032 0)
			(stroke
				(width 0.2032)
				(type default)
			)
			(layer "F.SilkS")
		)
		(fp_rect
			(start -0.5842 1.3335)
			(end 0.5842 -1.3335)
			(stroke
				(width 0)
				(type default)
			)
			(fill no)
			(layer "F.CrtYd")
		)
		(fp_rect
			(start -0.5842 1.3335)
			(end 0.5842 -1.3335)
			(stroke
				(width 0)
				(type default)
			)
			(fill no)
			(layer "F.Fab")
		)
		(pad "1" smd custom
			(at 0 -0.762 180)
			(size 0.2159 0.2159)
			(layers "F.Cu" "F.Mask" "F.Paste")
			(net "P5V_B")
			(options
				(clearance outline)
				(anchor circle)
			)
			(primitives
				(gr_poly
					(pts
						(arc
							(start -0.3302 -0.4318)
							(mid -0.402042 -0.402042)
							(end -0.4318 -0.3302)
						)
						(arc
							(start -0.4318 0.3302)
							(mid -0.402042 0.402042)
							(end -0.3302 0.4318)
						)
						(arc
							(start 0.3302 0.4318)
							(mid 0.402042 0.402042)
							(end 0.4318 0.3302)
						)
						(arc
							(start 0.4318 -0.3302)
							(mid 0.402042 -0.402042)
							(end 0.3302 -0.4318)
						)
					)
					(width 0)
					(fill yes)
				)
			)
		)
		(pad "2" smd custom
			(at 0 0.762 180)
			(size 0.2159 0.2159)
			(layers "F.Cu" "F.Mask" "F.Paste")
			(net "DRV_ACT_31")
			(options
				(clearance outline)
				(anchor circle)
			)
			(primitives
				(gr_poly
					(pts
						(arc
							(start -0.3302 -0.4318)
							(mid -0.402042 -0.402042)
							(end -0.4318 -0.3302)
						)
						(arc
							(start -0.4318 0.3302)
							(mid -0.402042 0.402042)
							(end -0.3302 0.4318)
						)
						(arc
							(start 0.3302 0.4318)
							(mid 0.402042 0.402042)
							(end 0.4318 0.3302)
						)
						(arc
							(start 0.4318 -0.3302)
							(mid 0.402042 -0.402042)
							(end 0.3302 -0.4318)
						)
					)
					(width 0)
					(fill yes)
				)
			)
		)
	)
	(footprint ""
		(layer "F.Cu")
		(at 353.184714 -44.219368 -90)
		(property "Reference" "C441"
			(at 0 0 270)
			(layer "F.SilkS")
			(hide yes)
			(effects
				(font
					(size 1.27 1.27)
				)
			)
		)
		(property "Value" "SCD01U16V1KX-GP"
			(at -2.8321 -1.7399 270)
			(unlocked yes)
			(layer "F.Fab")
			(hide yes)
			(effects
				(font
					(size 1.016 1.016)
					(thickness 0.1524)
				)
			)
		)
		(property "Device Type" "C0201H13"
			(at -2.8321 -3.2639 270)
			(unlocked yes)
			(layer "F.Fab")
			(hide yes)
			(effects
				(font
					(size 1.016 1.016)
					(thickness 0.1524)
				)
			)
		)
		(duplicate_pad_numbers_are_jumpers no)
		(fp_rect
			(start -0.2794 0.6477)
			(end 0.2794 -0.6477)
			(stroke
				(width 0)
				(type default)
			)
			(fill no)
			(layer "F.CrtYd")
		)
		(fp_rect
			(start -0.2794 0.6477)
			(end 0.2794 -0.6477)
			(stroke
				(width 0)
				(type default)
			)
			(fill no)
			(layer "F.Fab")
		)
		(pad "1" smd custom
			(at 0 -0.2794 270)
			(size 0.0762 0.0762)
			(layers "F.Cu" "F.Mask" "F.Paste")
			(net "SAS_HDD_RX_N31")
			(options
				(clearance outline)
				(anchor circle)
			)
			(primitives
				(gr_poly
					(pts
						(arc
							(start 0.1524 -0.127)
							(mid 0.137521 -0.162921)
							(end 0.1016 -0.1778)
						)
						(arc
							(start -0.1016 -0.1778)
							(mid -0.137521 -0.162921)
							(end -0.1524 -0.127)
						)
						(arc
							(start -0.1524 0.127)
							(mid -0.137521 0.162921)
							(end -0.1016 0.1778)
						)
						(arc
							(start 0.1016 0.1778)
							(mid 0.137521 0.162921)
							(end 0.1524 0.127)
						)
					)
					(width 0)
					(fill yes)
				)
			)
		)
		(pad "2" smd custom
			(at 0 0.2794 270)
			(size 0.0762 0.0762)
			(layers "F.Cu" "F.Mask" "F.Paste")
			(net "PHY_SCC_A_TO_DRV_A_31_DN")
			(options
				(clearance outline)
				(anchor circle)
			)
			(primitives
				(gr_poly
					(pts
						(arc
							(start 0.1524 -0.127)
							(mid 0.137521 -0.162921)
							(end 0.1016 -0.1778)
						)
						(arc
							(start -0.1016 -0.1778)
							(mid -0.137521 -0.162921)
							(end -0.1524 -0.127)
						)
						(arc
							(start -0.1524 0.127)
							(mid -0.137521 0.162921)
							(end -0.1016 0.1778)
						)
						(arc
							(start 0.1016 0.1778)
							(mid 0.137521 0.162921)
							(end 0.1524 0.127)
						)
					)
					(width 0)
					(fill yes)
				)
			)
		)
	)
	(footprint ""
		(layer "F.Cu")
		(at 464.8073 -287.825942 90)
		(property "Reference" "C179"
			(at 0 0 90)
			(layer "F.SilkS")
			(hide yes)
			(effects
				(font
					(size 1.27 1.27)
				)
			)
		)
		(property "Value" "SCD033U25V2KX-GP"
			(at 1.1811 -2.7051 90)
			(unlocked yes)
			(layer "F.Fab")
			(hide yes)
			(effects
				(font
					(size 1.016 1.016)
					(thickness 0.1524)
				)
			)
		)
		(property "Device Type" "C402H22"
			(at 1.1811 -4.2291 90)
			(unlocked yes)
			(layer "F.Fab")
			(hide yes)
			(effects
				(font
					(size 1.016 1.016)
					(thickness 0.1524)
				)
			)
		)
		(duplicate_pad_numbers_are_jumpers no)
		(fp_rect
			(start -0.4318 0.9525)
			(end 0.4318 -0.9525)
			(stroke
				(width 0)
				(type default)
			)
			(fill no)
			(layer "F.CrtYd")
		)
		(fp_rect
			(start -0.4318 0.9525)
			(end 0.4318 -0.9525)
			(stroke
				(width 0)
				(type default)
			)
			(fill no)
			(layer "F.Fab")
		)
		(pad "1" smd custom
			(at 0 -0.4445 90)
			(size 0.1524 0.1524)
			(layers "F.Cu" "F.Mask" "F.Paste")
			(net "P12V_A")
			(options
				(clearance outline)
				(anchor circle)
			)
			(primitives
				(gr_poly
					(pts
						(arc
							(start 0.3048 -0.2032)
							(mid 0.275042 -0.275042)
							(end 0.2032 -0.3048)
						)
						(arc
							(start -0.2032 -0.3048)
							(mid -0.275042 -0.275042)
							(end -0.3048 -0.2032)
						)
						(arc
							(start -0.3048 0.2032)
							(mid -0.275042 0.275042)
							(end -0.2032 0.3048)
						)
						(arc
							(start 0.2032 0.3048)
							(mid 0.275042 0.275042)
							(end 0.3048 0.2032)
						)
					)
					(width 0)
					(fill yes)
				)
			)
		)
		(pad "2" smd custom
			(at 0 0.4445 90)
			(size 0.1524 0.1524)
			(layers "F.Cu" "F.Mask" "F.Paste")
			(net "SW_HDD_N10")
			(options
				(clearance outline)
				(anchor circle)
			)
			(primitives
				(gr_poly
					(pts
						(arc
							(start 0.3048 -0.2032)
							(mid 0.275042 -0.275042)
							(end 0.2032 -0.3048)
						)
						(arc
							(start -0.2032 -0.3048)
							(mid -0.275042 -0.275042)
							(end -0.3048 -0.2032)
						)
						(arc
							(start -0.3048 0.2032)
							(mid -0.275042 0.275042)
							(end -0.2032 0.3048)
						)
						(arc
							(start 0.2032 0.3048)
							(mid 0.275042 0.275042)
							(end 0.3048 0.2032)
						)
					)
					(width 0)
					(fill yes)
				)
			)
		)
	)
)
